FILE_TYPE = MACRO_DRAWING;
SET COLOR_WIRE YELLOW;
SET COLOR_PROP ORANGE;
SET COLOR_DOT WHITE;
SET COLOR_ARC YELLOW;
SET COLOR_BODY GREEN;
SET COLOR_NOTE PURPLE;
SET PROP_DISPLAY VALUE;
SET PAGE_NUMBER P281;
FORCEADD QUANTA_TITLE_BLOCK_C..1
(-100 100);
FORCEPROP 1 LAST CUSTOM_TXT_CDS <NAME_2>
J 0
(-3275 150);
FORCEPROP 1 LAST CUSTOM_TXT_CDS <NAME_1>
J 0
(-3275 275);
FORCEPROP 1 LAST CUSTOM_TXT_CDS <Q_NUMBER>
J 0
(-1503 203);
DISPLAY 1.212766 (-1503 203);
FORCEPROP 1 LAST CUSTOM_TXT_CDS <Q_PROJ>
J 0
(-2482 202);
DISPLAY 1.212766 (-2482 202);
FORCEPROP 1 LAST CUSTOM_TXT_CDS <Q_REV>
J 0
(-284 203);
DISPLAY 1.212766 (-284 203);
FORCEPROP 1 LAST CUSTOM_TXT_CDS <CON_LAST_MODIFIED>
J 0
(-1985 115);
DISPLAY 0.978723 (-1985 115);
FORCEPROP 1 LAST CUSTOM_TXT_CDS <CON_PAGE_NUM> OF <CON_TOTAL_PAGES>
J 0
(-546 118);
DISPLAY 0.978723 (-546 118);
FORCEPROP 1 LAST Q_TITLE BLANK
J 0
(-9466 126);
DISPLAY 2.446809 (-9466 126);
PAINT GREEN (-9466 126);
FORCEPROP 1 LAST Q_DEPT 
J 1
(-3863 149);
DISPLAY 1.957447 (-3863 149);
PAINT GREEN (-3863 149);
FORCEPROP 2 LAST CDS_XR_PAGE_TITLE CR-295 : @S9S_MB_2U_LIB.S9S_MB_2U(SCH_1):PAGE295
J 0
(-7990 5350);
DISPLAY 0.638298 (-7990 5350);
PAINT PINK (-7990 5350);
DISPLAY INVISIBLE (-7990 5350);
FORCEPROP 2 LAST CDS_LIB pure_quanta
J 0
(-100 100);
DISPLAY INVISIBLE (-100 100);
FORCEPROP 1 LAST CDS_LMAN_SYM_OUTLINE -9475,6775,100,-125
J 0
(-100 100);
DISPLAY 0.468085 (-100 100);
PAINT GREEN (-100 100);
DISPLAY INVISIBLE (-100 100);
FORCEPROP 2 LAST PAGE_BORDER TRUE
J 0
(-7990 5350);
DISPLAY 0.638298 (-7990 5350);
PAINT PINK (-7990 5350);
DISPLAY INVISIBLE (-7990 5350);
FORCEPROP 1 LAST COMMENT_BODY TRUE
J 0
(-88 87);
DISPLAY 0.978723 (-88 87);
PAINT GREEN (-88 87);
DISPLAY INVISIBLE (-88 87);
FORCEPROP 2 LAST CUSTOM_TXT_CDS <XR_PAGE_TITLE>
J 0
(-7990 5350);
DISPLAY 0.638298 (-7990 5350);
PAINT PINK (-7990 5350);
DISPLAY INVISIBLE (-7990 5350);
FORCEPROP 0 LAST CDS_CON_LAST_MODIFIED Thu Aug 24 16:17:05 2023
J 0
(-1985 115);
DISPLAY INVISIBLE (-1985 115);
QUIT
